(kicad_pcb
	(version 20241229)
	(generator "pcbnew")
	(generator_version "9.0")
	(general
		(thickness 1.711)
		(legacy_teardrops no)
	)
	(paper "A4")
	(title_block
		(title "Antmicro Baseboard for Jetson AGX Thor")
		(date "2026-02-18")
		(rev "1.1.0")
		(company "Antmicro Ltd")
		(comment 1 "www.antmicro.com")
		(comment 9 "footprints 619-622 of 1170")
	)
	(layers
		(0 "F.Cu" signal)
		(4 "In1.Cu" signal)
		(6 "In2.Cu" signal)
		(8 "In3.Cu" signal)
		(10 "In4.Cu" jumper)
		(12 "In5.Cu" signal)
		(14 "In6.Cu" signal)
		(16 "In7.Cu" signal)
		(18 "In8.Cu" signal)
		(2 "B.Cu" signal)
		(9 "F.Adhes" user "F.Adhesive")
		(11 "B.Adhes" user "B.Adhesive")
		(13 "F.Paste" user)
		(15 "B.Paste" user)
		(5 "F.SilkS" user "F.Silkscreen")
		(7 "B.SilkS" user "B.Silkscreen")
		(1 "F.Mask" user)
		(3 "B.Mask" user)
		(17 "Dwgs.User" user "User.Drawings")
		(19 "Cmts.User" user "User.Comments")
		(21 "Eco1.User" user "User.Eco1")
		(23 "Eco2.User" user "User.Eco2")
		(25 "Edge.Cuts" user)
		(27 "Margin" user)
		(31 "F.CrtYd" user "F.Courtyard")
		(29 "B.CrtYd" user "B.Courtyard")
		(35 "F.Fab" user)
		(33 "B.Fab" user)
	)
	(footprint "antmicro-footprints:LED_0603_1608Metric_G"
		(layer "F.Cu")
		(at 168.5 55.3 -90)
		(descr "LED SMD 0603 Green")
		(tags "LED SMD 0603 Green")
		(property "Reference" "D3"
			(at -0.18 1.49875 90)
			(layer "F.SilkS")
			(effects
				(font
					(size 0.7 0.7)
					(thickness 0.15)
				)
				(justify right top)
			)
		)
		(property "Value" "LED_G_0603_LTST-C190GKT"
			(at -0.001 1.599 90)
			(layer "F.Fab")
			(effects
				(font
					(size 0.7 0.7)
					(thickness 0.15)
				)
				(justify right top)
			)
		)
		(property "Datasheet" "https://media.digikey.com/pdf/Data%20Sheets/Lite-On%20PDFs/LTST-C190GKT.pdf"
			(at 0 0 90)
			(layer "F.Fab")
			(hide yes)
			(effects
				(font
					(size 1.27 1.27)
					(thickness 0.15)
				)
			)
		)
		(property "Description" "LED, Green, SMD, 0603, 20 mA, 2.1 V, 569 nm"
			(at 0 0 90)
			(layer "F.Fab")
			(hide yes)
			(effects
				(font
					(size 1.27 1.27)
					(thickness 0.15)
				)
			)
		)
		(property "MPN" "LTST-C190GKT"
			(at 0 0 270)
			(unlocked yes)
			(layer "F.Fab")
			(hide yes)
			(effects
				(font
					(size 1 1)
					(thickness 0.15)
				)
			)
		)
		(property "Manufacturer" "Lite-On"
			(at 0 0 270)
			(unlocked yes)
			(layer "F.Fab")
			(hide yes)
			(effects
				(font
					(size 1 1)
					(thickness 0.15)
				)
			)
		)
		(property "Author" "Antmicro"
			(at 0 0 270)
			(unlocked yes)
			(layer "F.Fab")
			(hide yes)
			(effects
				(font
					(size 1 1)
					(thickness 0.15)
				)
			)
		)
		(property "License" "Apache-2.0"
			(at 0 0 270)
			(unlocked yes)
			(layer "F.Fab")
			(hide yes)
			(effects
				(font
					(size 1 1)
					(thickness 0.15)
				)
			)
		)
		(property "Color" "Green"
			(at 0 0 270)
			(unlocked yes)
			(layer "F.Fab")
			(hide yes)
			(effects
				(font
					(size 1 1)
					(thickness 0.15)
				)
			)
		)
		(sheetname "/Power/")
		(sheetfile "power.kicad_sch")
		(attr smd)
		(fp_line
			(start 0.22 0.35)
			(end -0.22 0.35)
			(stroke
				(width 0.15)
				(type solid)
			)
			(layer "F.SilkS")
		)
		(fp_line
			(start -0.094672 0.201008)
			(end -0.094672 -0.198992)
			(stroke
				(width 0.1)
				(type solid)
			)
			(layer "F.SilkS")
		)
		(fp_line
			(start 0.105328 0.201008)
			(end -0.094672 0.001008)
			(stroke
				(width 0.1)
				(type solid)
			)
			(layer "F.SilkS")
		)
		(fp_line
			(start 0.105328 0.201008)
			(end 0.105328 -0.198992)
			(stroke
				(width 0.1)
				(type solid)
			)
			(layer "F.SilkS")
		)
		(fp_line
			(start -0.094672 0.001008)
			(end -0.24 0.001008)
			(stroke
				(width 0.1)
				(type solid)
			)
			(layer "F.SilkS")
		)
		(fp_line
			(start -0.094672 0.001008)
			(end 0.105328 -0.198992)
			(stroke
				(width 0.1)
				(type solid)
			)
			(layer "F.SilkS")
		)
		(fp_line
			(start 0.105328 0.001008)
			(end 0.24 0.001)
			(stroke
				(width 0.1)
				(type solid)
			)
			(layer "F.SilkS")
		)
		(fp_line
			(start -1.18 -0.319)
			(end -1.18 0.321)
			(stroke
				(width 0.15)
				(type solid)
			)
			(layer "F.SilkS")
		)
		(fp_line
			(start 0.22 -0.35)
			(end -0.22 -0.35)
			(stroke
				(width 0.15)
				(type solid)
			)
			(layer "F.SilkS")
		)
		(fp_rect
			(start 1.25 0.65)
			(end -1.25 -0.65)
			(stroke
				(width 0.05)
				(type solid)
			)
			(fill no)
			(layer "F.CrtYd")
		)
		(fp_line
			(start -0.199 0.2)
			(end -0.199 0.1)
			(stroke
				(width 0.15)
				(type solid)
			)
			(layer "F.Fab")
		)
		(fp_line
			(start 0.201 0.2)
			(end 0.201 0)
			(stroke
				(width 0.15)
				(type solid)
			)
			(layer "F.Fab")
		)
		(fp_line
			(start -0.199 0)
			(end -0.597 0)
			(stroke
				(width 0.15)
				(type solid)
			)
			(layer "F.Fab")
		)
		(fp_line
			(start -0.101 0)
			(end 0.201 0.2)
			(stroke
				(width 0.15)
				(type solid)
			)
			(layer "F.Fab")
		)
		(fp_line
			(start 0.201 0)
			(end 0.201 -0.202)
			(stroke
				(width 0.15)
				(type solid)
			)
			(layer "F.Fab")
		)
		(fp_line
			(start 0.599 0)
			(end 0.201 0)
			(stroke
				(width 0.15)
				(type solid)
			)
			(layer "F.Fab")
		)
		(fp_line
			(start -0.199 -0.202)
			(end -0.199 0.1)
			(stroke
				(width 0.15)
				(type solid)
			)
			(layer "F.Fab")
		)
		(fp_line
			(start 0.201 -0.202)
			(end -0.101 0)
			(stroke
				(width 0.15)
				(type solid)
			)
			(layer "F.Fab")
		)
		(fp_rect
			(start 0.848 0.4)
			(end -0.85 -0.402)
			(stroke
				(width 0.15)
				(type solid)
			)
			(fill no)
			(layer "F.Fab")
		)
		(fp_text user "Author: Antmicro"
			(at -1.4224 4.799 90)
			(layer "F.Fab")
			(effects
				(font
					(size 0.7 0.7)
					(thickness 0.15)
				)
				(justify right top)
			)
		)
		(fp_text user "License: Apache-2.0"
			(at -1.4224 3.599 90)
			(layer "F.Fab")
			(effects
				(font
					(size 0.7 0.7)
					(thickness 0.15)
				)
				(justify right top)
			)
		)
		(fp_text user "${REFERENCE}"
			(at -1.4224 5.999 90)
			(layer "F.Fab")
			(effects
				(font
					(size 0.7 0.7)
					(thickness 0.15)
				)
				(justify right top)
			)
		)
		(pad "1" smd roundrect
			(at -0.7 0 90)
			(size 0.8 1)
			(layers "F.Cu" "F.Mask" "F.Paste")
			(roundrect_rratio 0.2)
			(net 1 "GND")
			(pinfunction "C")
			(pintype "passive")
		)
		(pad "2" smd roundrect
			(at 0.7 0 90)
			(size 0.8 1)
			(layers "F.Cu" "F.Mask" "F.Paste")
			(roundrect_rratio 0.2)
			(net 526 "Net-(D3-A)")
			(pinfunction "A")
			(pintype "passive")
		)
	)
	(footprint "antmicro-footprints:LED_0603_1608Metric_G"
		(layer "B.Cu")
		(at 108.555 140.77 90)
		(descr "LED SMD 0603 Green")
		(tags "LED SMD 0603 Green")
		(property "Reference" "D34"
			(at -0.98 -1.645 90)
			(layer "B.SilkS")
			(effects
				(font
					(size 0.7 0.7)
					(thickness 0.15)
				)
				(justify right top mirror)
			)
		)
		(property "Value" "LED_G_0603_LTST-C190GKT"
			(at -0.001 -1.599 90)
			(layer "B.Fab")
			(effects
				(font
					(size 0.7 0.7)
					(thickness 0.15)
				)
				(justify right top mirror)
			)
		)
		(property "Datasheet" "https://media.digikey.com/pdf/Data%20Sheets/Lite-On%20PDFs/LTST-C190GKT.pdf"
			(at 0 0 90)
			(layer "B.Fab")
			(hide yes)
			(effects
				(font
					(size 1.27 1.27)
					(thickness 0.15)
				)
				(justify mirror)
			)
		)
		(property "Description" "LED, Green, SMD, 0603, 20 mA, 2.1 V, 569 nm"
			(at 0 0 90)
			(layer "B.Fab")
			(hide yes)
			(effects
				(font
					(size 1.27 1.27)
					(thickness 0.15)
				)
				(justify mirror)
			)
		)
		(property "MPN" "LTST-C190GKT"
			(at 0 0 270)
			(unlocked yes)
			(layer "B.Fab")
			(hide yes)
			(effects
				(font
					(size 1 1)
					(thickness 0.15)
				)
				(justify mirror)
			)
		)
		(property "Manufacturer" "Lite-On"
			(at 0 0 270)
			(unlocked yes)
			(layer "B.Fab")
			(hide yes)
			(effects
				(font
					(size 1 1)
					(thickness 0.15)
				)
				(justify mirror)
			)
		)
		(property "Author" "Antmicro"
			(at 0 0 270)
			(unlocked yes)
			(layer "B.Fab")
			(hide yes)
			(effects
				(font
					(size 1 1)
					(thickness 0.15)
				)
				(justify mirror)
			)
		)
		(property "License" "Apache-2.0"
			(at 0 0 270)
			(unlocked yes)
			(layer "B.Fab")
			(hide yes)
			(effects
				(font
					(size 1 1)
					(thickness 0.15)
				)
				(justify mirror)
			)
		)
		(property "Public" "False"
			(at 0 0 270)
			(unlocked yes)
			(layer "B.Fab")
			(hide yes)
			(effects
				(font
					(size 1 1)
					(thickness 0.15)
				)
				(justify mirror)
			)
		)
		(property "Color" "Green"
			(at 0 0 270)
			(unlocked yes)
			(layer "B.Fab")
			(hide yes)
			(effects
				(font
					(size 1 1)
					(thickness 0.15)
				)
				(justify mirror)
			)
		)
		(sheetname "/M.2/")
		(sheetfile "m2.kicad_sch")
		(attr smd)
		(fp_line
			(start 0.22 -0.35)
			(end -0.22 -0.35)
			(stroke
				(width 0.15)
				(type solid)
			)
			(layer "B.SilkS")
		)
		(fp_line
			(start 0.105328 -0.201008)
			(end -0.094672 -0.001008)
			(stroke
				(width 0.1)
				(type solid)
			)
			(layer "B.SilkS")
		)
		(fp_line
			(start 0.105328 -0.201008)
			(end 0.105328 0.198992)
			(stroke
				(width 0.1)
				(type solid)
			)
			(layer "B.SilkS")
		)
		(fp_line
			(start -0.094672 -0.201008)
			(end -0.094672 0.198992)
			(stroke
				(width 0.1)
				(type solid)
			)
			(layer "B.SilkS")
		)
		(fp_line
			(start 0.105328 -0.001008)
			(end 0.24 -0.001)
			(stroke
				(width 0.1)
				(type solid)
			)
			(layer "B.SilkS")
		)
		(fp_line
			(start -0.094672 -0.001008)
			(end -0.24 -0.001008)
			(stroke
				(width 0.1)
				(type solid)
			)
			(layer "B.SilkS")
		)
		(fp_line
			(start -0.094672 -0.001008)
			(end 0.105328 0.198992)
			(stroke
				(width 0.1)
				(type solid)
			)
			(layer "B.SilkS")
		)
		(fp_line
			(start -1.18 0.319)
			(end -1.18 -0.321)
			(stroke
				(width 0.15)
				(type solid)
			)
			(layer "B.SilkS")
		)
		(fp_line
			(start 0.22 0.35)
			(end -0.22 0.35)
			(stroke
				(width 0.15)
				(type solid)
			)
			(layer "B.SilkS")
		)
		(fp_rect
			(start 1.25 -0.65)
			(end -1.25 0.65)
			(stroke
				(width 0.05)
				(type solid)
			)
			(fill no)
			(layer "B.CrtYd")
		)
		(fp_line
			(start 0.201 -0.2)
			(end 0.201 0)
			(stroke
				(width 0.15)
				(type solid)
			)
			(layer "B.Fab")
		)
		(fp_line
			(start -0.199 -0.2)
			(end -0.199 -0.1)
			(stroke
				(width 0.15)
				(type solid)
			)
			(layer "B.Fab")
		)
		(fp_line
			(start 0.599 0)
			(end 0.201 0)
			(stroke
				(width 0.15)
				(type solid)
			)
			(layer "B.Fab")
		)
		(fp_line
			(start 0.201 0)
			(end 0.201 0.202)
			(stroke
				(width 0.15)
				(type solid)
			)
			(layer "B.Fab")
		)
		(fp_line
			(start -0.101 0)
			(end 0.201 -0.2)
			(stroke
				(width 0.15)
				(type solid)
			)
			(layer "B.Fab")
		)
		(fp_line
			(start -0.199 0)
			(end -0.597 0)
			(stroke
				(width 0.15)
				(type solid)
			)
			(layer "B.Fab")
		)
		(fp_line
			(start 0.201 0.202)
			(end -0.101 0)
			(stroke
				(width 0.15)
				(type solid)
			)
			(layer "B.Fab")
		)
		(fp_line
			(start -0.199 0.202)
			(end -0.199 -0.1)
			(stroke
				(width 0.15)
				(type solid)
			)
			(layer "B.Fab")
		)
		(fp_rect
			(start 0.848 -0.4)
			(end -0.85 0.402)
			(stroke
				(width 0.15)
				(type solid)
			)
			(fill no)
			(layer "B.Fab")
		)
		(fp_text user "License: Apache-2.0"
			(at -1.4224 -3.599 90)
			(layer "B.Fab")
			(effects
				(font
					(size 0.7 0.7)
					(thickness 0.15)
				)
				(justify right top mirror)
			)
		)
		(fp_text user "${REFERENCE}"
			(at -1.4224 -5.999 90)
			(layer "B.Fab")
			(effects
				(font
					(size 0.7 0.7)
					(thickness 0.15)
				)
				(justify right top mirror)
			)
		)
		(fp_text user "Author: Antmicro"
			(at -1.4224 -4.799 90)
			(layer "B.Fab")
			(effects
				(font
					(size 0.7 0.7)
					(thickness 0.15)
				)
				(justify right top mirror)
			)
		)
		(pad "1" smd roundrect
			(at -0.7 0 270)
			(size 0.8 1)
			(layers "B.Cu" "B.Mask" "B.Paste")
			(roundrect_rratio 0.2)
			(net 35 "/M.2/~{LED_2}")
			(pinfunction "C")
			(pintype "passive")
		)
		(pad "2" smd roundrect
			(at 0.7 0 270)
			(size 0.8 1)
			(layers "B.Cu" "B.Mask" "B.Paste")
			(roundrect_rratio 0.2)
			(net 546 "Net-(D34-A)")
			(pinfunction "A")
			(pintype "passive")
		)
	)
	(footprint "antmicro-footprints:R_0402_1005Metric"
		(layer "B.Cu")
		(at 92.87 149.209999)
		(descr "Resistor SMD 0402")
		(tags "resistor SMD 0402")
		(property "Reference" "R201"
			(at 0.85 -0.369264 0)
			(layer "B.SilkS")
			(effects
				(font
					(size 0.7 0.7)
					(thickness 0.15)
				)
				(justify right top mirror)
			)
		)
		(property "Value" "R_0R_0402"
			(at -1.011843 -1.772046 0)
			(layer "B.Fab")
			(effects
				(font
					(size 0.7 0.7)
					(thickness 0.15)
				)
				(justify right top mirror)
			)
		)
		(property "Datasheet" "https://industrial.panasonic.com/cdbs/www-data/pdf/RDA0000/AOA0000C301.pdf"
			(at 0 0 0)
			(layer "B.Fab")
			(hide yes)
			(effects
				(font
					(size 1.27 1.27)
					(thickness 0.15)
				)
				(justify mirror)
			)
		)
		(property "Description" "SMD Chip Resistor, Jumper, 0 ohm, 100 mW, 0402 [1005 Metric], Thick Film, General Purpose"
			(at 0 0 0)
			(layer "B.Fab")
			(hide yes)
			(effects
				(font
					(size 1.27 1.27)
					(thickness 0.15)
				)
				(justify mirror)
			)
		)
		(property "MPN" "ERJ2GE0R00X"
			(at 0 0 180)
			(unlocked yes)
			(layer "B.Fab")
			(hide yes)
			(effects
				(font
					(size 1 1)
					(thickness 0.15)
				)
				(justify mirror)
			)
		)
		(property "Manufacturer" "Panasonic"
			(at 0 0 180)
			(unlocked yes)
			(layer "B.Fab")
			(hide yes)
			(effects
				(font
					(size 1 1)
					(thickness 0.15)
				)
				(justify mirror)
			)
		)
		(property "License" "Apache-2.0"
			(at 0 0 180)
			(unlocked yes)
			(layer "B.Fab")
			(hide yes)
			(effects
				(font
					(size 1 1)
					(thickness 0.15)
				)
				(justify mirror)
			)
		)
		(property "Author" "Antmicro"
			(at 0 0 180)
			(unlocked yes)
			(layer "B.Fab")
			(hide yes)
			(effects
				(font
					(size 1 1)
					(thickness 0.15)
				)
				(justify mirror)
			)
		)
		(property "Val" "0R"
			(at 0 0 180)
			(unlocked yes)
			(layer "B.Fab")
			(hide yes)
			(effects
				(font
					(size 1 1)
					(thickness 0.15)
				)
				(justify mirror)
			)
		)
		(property "Tolerance" "~"
			(at 0 0 180)
			(unlocked yes)
			(layer "B.Fab")
			(hide yes)
			(effects
				(font
					(size 1 1)
					(thickness 0.15)
				)
				(justify mirror)
			)
		)
		(property "Current" "1A"
			(at 0 0 180)
			(unlocked yes)
			(layer "B.Fab")
			(hide yes)
			(effects
				(font
					(size 1 1)
					(thickness 0.15)
				)
				(justify mirror)
			)
		)
		(sheetname "/SoM_IO2/")
		(sheetfile "som_io2.kicad_sch")
		(attr smd)
		(fp_poly
			(pts
				(xy -0.925 0.47) (xy -0.925 -0.47) (xy 0.925 -0.47) (xy 0.925 0.47)
			)
			(stroke
				(width 0.05)
				(type default)
			)
			(fill no)
			(layer "B.CrtYd")
		)
		(fp_poly
			(pts
				(xy -0.5 0.25) (xy -0.5 -0.25) (xy 0.5 -0.25) (xy 0.5 0.25)
			)
			(stroke
				(width 0.15)
				(type solid)
			)
			(fill no)
			(layer "B.Fab")
		)
		(fp_text user "Author: Antmicro"
			(at -0.95 -4.169 0)
			(layer "B.Fab")
			(effects
				(font
					(size 0.7 0.7)
					(thickness 0.15)
				)
				(justify right top mirror)
			)
		)
		(fp_text user "License: Apache-2.0"
			(at -0.949999 -5.169 0)
			(layer "B.Fab")
			(effects
				(font
					(size 0.7 0.7)
					(thickness 0.15)
				)
				(justify right top mirror)
			)
		)
		(fp_text user "${REFERENCE}"
			(at -0.95 -3.168 0)
			(layer "B.Fab")
			(effects
				(font
					(size 0.7 0.7)
					(thickness 0.15)
				)
				(justify right top mirror)
			)
		)
		(pad "1" smd roundrect
			(at -0.48 0)
			(size 0.59 0.64)
			(layers "B.Cu" "B.Mask" "B.Paste")
			(roundrect_rratio 0.25)
			(net 843 "/Expansion connector/PCIe_{C2x1}.CLK+")
			(pintype "passive")
		)
		(pad "2" smd roundrect
			(at 0.48 0)
			(size 0.59 0.64)
			(layers "B.Cu" "B.Mask" "B.Paste")
			(roundrect_rratio 0.25)
			(net 720 "/SoM_IO2/PCIe_{C2x1}R_CLK+")
			(pintype "passive")
		)
	)
	(footprint "antmicro-footprints:R_0402_1005Metric"
		(layer "B.Cu")
		(at 195.6 131.65 -90)
		(descr "Resistor SMD 0402")
		(tags "resistor SMD 0402")
		(property "Reference" "R321"
			(at -1.3 0.588198 90)
			(layer "B.SilkS")
			(effects
				(font
					(size 0.7 0.7)
					(thickness 0.15)
				)
				(justify left bottom mirror)
			)
		)
		(property "Value" "R_10k_0402"
			(at -1.011843 -1.772047 90)
			(layer "B.Fab")
			(effects
				(font
					(size 0.7 0.7)
					(thickness 0.15)
				)
				(justify left bottom mirror)
			)
		)
		(property "Datasheet" "https://www.bourns.com/docs/product-datasheets/cr.pdf"
			(at 0 0 90)
			(layer "B.Fab")
			(hide yes)
			(effects
				(font
					(size 1.27 1.27)
					(thickness 0.15)
				)
				(justify mirror)
			)
		)
		(property "Description" "SMD Chip Resistor, 10 kohm, ± 1%, 62.5 mW, 0402 [1005 Metric], Thick Film, General Purpose"
			(at 0 0 90)
			(layer "B.Fab")
			(hide yes)
			(effects
				(font
					(size 1.27 1.27)
					(thickness 0.15)
				)
				(justify mirror)
			)
		)
		(property "Manufacturer" "Bourns"
			(at 0 0 90)
			(unlocked yes)
			(layer "B.Fab")
			(hide yes)
			(effects
				(font
					(size 1 1)
					(thickness 0.15)
				)
				(justify mirror)
			)
		)
		(property "MPN" "CR0402-FX-1002GLF"
			(at 0 0 90)
			(unlocked yes)
			(layer "B.Fab")
			(hide yes)
			(effects
				(font
					(size 1 1)
					(thickness 0.15)
				)
				(justify mirror)
			)
		)
		(property "Val" "10k"
			(at 0 0 90)
			(unlocked yes)
			(layer "B.Fab")
			(hide yes)
			(effects
				(font
					(size 1 1)
					(thickness 0.15)
				)
				(justify mirror)
			)
		)
		(property "License" "Apache-2.0"
			(at 0 0 90)
			(unlocked yes)
			(layer "B.Fab")
			(hide yes)
			(effects
				(font
					(size 1 1)
					(thickness 0.15)
				)
				(justify mirror)
			)
		)
		(property "Author" "Antmicro"
			(at 0 0 90)
			(unlocked yes)
			(layer "B.Fab")
			(hide yes)
			(effects
				(font
					(size 1 1)
					(thickness 0.15)
				)
				(justify mirror)
			)
		)
		(property "Tolerance" "1%"
			(at 0 0 90)
			(unlocked yes)
			(layer "B.Fab")
			(hide yes)
			(effects
				(font
					(size 1 1)
					(thickness 0.15)
				)
				(justify mirror)
			)
		)
		(sheetname "/USB Hub/")
		(sheetfile "usb_hub.kicad_sch")
		(attr smd exclude_from_pos_files exclude_from_bom dnp)
		(fp_rect
			(start -0.925 0.47)
			(end 0.925 -0.47)
			(stroke
				(width 0.05)
				(type default)
			)
			(fill no)
			(layer "B.CrtYd")
		)
		(fp_rect
			(start -0.5 0.25)
			(end 0.5 -0.25)
			(stroke
				(width 0.15)
				(type solid)
			)
			(fill no)
			(layer "B.Fab")
		)
		(fp_text user "License: Apache-2.0"
			(at -0.95 -5.169 90)
			(layer "B.Fab")
			(effects
				(font
					(size 0.7 0.7)
					(thickness 0.15)
				)
				(justify left bottom mirror)
			)
		)
		(fp_text user "${REFERENCE}"
			(at -0.95 -3.168 90)
			(layer "B.Fab")
			(effects
				(font
					(size 0.7 0.7)
					(thickness 0.15)
				)
				(justify left bottom mirror)
			)
		)
		(fp_text user "Author: Antmicro"
			(at -0.95 -4.169 90)
			(layer "B.Fab")
			(effects
				(font
					(size 0.7 0.7)
					(thickness 0.15)
				)
				(justify left bottom mirror)
			)
		)
		(pad "1" smd roundrect
			(at -0.48 0 270)
			(size 0.59 0.64)
			(layers "B.Cu" "B.Mask" "B.Paste")
			(roundrect_rratio 0.25)
			(net 930 "/USB Hub/HUB_SPI_CE_N")
			(pintype "passive")
		)
		(pad "2" smd roundrect
			(at 0.48 0 270)
			(size 0.59 0.64)
			(layers "B.Cu" "B.Mask" "B.Paste")
			(roundrect_rratio 0.25)
			(net 2 "+3V3")
			(pintype "passive")
		)
	)
)
